# BASEBOARD_FAB2 (Tioga Pass) — schematic netlist excerpt (pin names and nets, part order shuffled) for the footprints in the layout excerpt that follows; sources: Cadence DE-HDL packaged netlist, KiCad conversion of Wiwynn_Tioga_Pass_MB.brd

C9M7  CAP_A  0.1UF 16V 10% X7R  pkg 0402V  page 163 : A = P3V3_STBY ; B = GND
R9R12  RES  0.0 5% CHIP  pkg 0402  page 181 : A = FAN_TACH2 ; B = FAN_TACH2_R
C3N24  CAP_A  22.0UF 4V 20% X6S  pkg 0603V  page 132 : A = PVNN_PCH_STBY ; B = GND

(kicad_pcb
	(version 20260206)
	(generator "pcbnew")
	(generator_version "10.0")
	(general
		(thickness 1.6)
		(legacy_teardrops no)
	)
	(paper "A4")
	(title_block
		(title "Wiwynn_Tioga_Pass_MB.brd")
		(comment 1 "Tioga Pass / footprints 3349-3351 of 4770")
	)
	(layers
		(0 "F.Cu" signal "TOP")
		(4 "In1.Cu" signal "L2GND")
		(6 "In2.Cu" signal "L3")
		(8 "In3.Cu" signal "L4GND")
		(10 "In4.Cu" signal "L5")
		(12 "In5.Cu" signal "L6GND")
		(14 "In6.Cu" signal "L7VCC")
		(16 "In7.Cu" signal "L8VCC")
		(18 "In8.Cu" signal "L9GND")
		(20 "In9.Cu" signal "L10")
		(22 "In10.Cu" signal "L11GND")
		(24 "In11.Cu" signal "L12")
		(26 "In12.Cu" signal "L13GND")
		(2 "B.Cu" signal "BOTTOM")
		(9 "F.Adhes" user "F.Adhesive")
		(11 "B.Adhes" user "B.Adhesive")
		(13 "F.Paste" user "Package Geometry/Pastemask Top")
		(15 "B.Paste" user "Package Geometry/Pastemask Bottom")
		(5 "F.SilkS" user "Ref Des/Silkscreen Top")
		(7 "B.SilkS" user "Ref Des/Silkscreen Bottom")
		(1 "F.Mask" user "Board Geometry/Soldermask Top")
		(3 "B.Mask" user "Board Geometry/Soldermask Bottom")
		(17 "Dwgs.User" user "User.Drawings")
		(19 "Cmts.User" user "User.Comments")
		(21 "Eco1.User" user "User.Eco1")
		(23 "Eco2.User" user "User.Eco2")
		(25 "Edge.Cuts" user "Board Geometry/Outline")
		(27 "Margin" user)
		(31 "F.CrtYd" user "Package Geometry/Place Bound Top")
		(29 "B.CrtYd" user "Package Geometry/Place Bound Bottom")
		(35 "F.Fab" user "Ref Des/Assembly Top")
		(33 "B.Fab" user "Ref Des/Assembly Bottom")
	)
	(footprint ""
		(layer "B.Cu")
		(at 368.935 -104.902 -90)
		(property "Reference" "C3N24"
			(at 0 0 90)
			(layer "B.SilkS")
			(hide yes)
			(effects
				(font
					(size 1.27 1.27)
				)
				(justify mirror)
			)
		)
		(property "Value" ""
			(at 0 0 90)
			(layer "B.Fab")
			(effects
				(font
					(size 1.27 1.27)
				)
				(justify mirror)
			)
		)
		(duplicate_pad_numbers_are_jumpers no)
		(fp_poly
			(pts
				(xy 0.4953 -0.2032) (xy -0.4953 -0.2032) (xy -0.4953 1.6002) (xy 0.4953 1.6002)
			)
			(stroke
				(width 0)
				(type default)
			)
			(fill no)
			(layer "B.CrtYd")
		)
		(fp_line
			(start -0.4953 1.6002)
			(end 0.4953 1.6002)
			(stroke
				(width 0.1)
				(type default)
			)
			(layer "B.Fab")
		)
		(fp_line
			(start 0.4953 1.6002)
			(end 0.4953 -0.2032)
			(stroke
				(width 0.1)
				(type default)
			)
			(layer "B.Fab")
		)
		(fp_line
			(start -0.4953 -0.2032)
			(end -0.4953 1.6002)
			(stroke
				(width 0.1)
				(type default)
			)
			(layer "B.Fab")
		)
		(fp_line
			(start 0.4953 -0.2032)
			(end -0.4953 -0.2032)
			(stroke
				(width 0.1)
				(type default)
			)
			(layer "B.Fab")
		)
		(pad "1" smd rect
			(at 0 0 90)
			(size 0.762 0.889)
			(layers "B.Cu" "B.Mask" "B.Paste")
			(net "PVNN_PCH_STBY")
		)
		(pad "2" smd rect
			(at 0 1.397 90)
			(size 0.762 0.889)
			(layers "B.Cu" "B.Mask" "B.Paste")
			(net "GND")
		)
		(zone
			(layer "B.Cu")
			(hatch none 0.5)
			(connect_pads
				(clearance 0)
			)
			(min_thickness 0.25)
			(keepout
				(tracks not_allowed)
				(vias allowed)
				(pads allowed)
				(copperpour not_allowed)
				(footprints allowed)
			)
			(placement
				(enabled no)
				(sheetname "")
			)
			(fill
				(thermal_gap 0.5)
				(thermal_bridge_width 0.5)
				(island_removal_mode 0)
			)
			(polygon
				(pts
					(xy 368.4905 -104.521) (xy 368.4905 -105.283) (xy 367.9825 -105.283) (xy 367.9825 -104.521)
				)
			)
		)
	)
	(footprint ""
		(layer "B.Cu")
		(at -4.36626 -120.60936)
		(property "Reference" "C9M7"
			(at 0 0 0)
			(layer "B.SilkS")
			(hide yes)
			(effects
				(font
					(size 1.27 1.27)
				)
				(justify mirror)
			)
		)
		(property "Value" ""
			(at 0 0 0)
			(layer "B.Fab")
			(effects
				(font
					(size 1.27 1.27)
				)
				(justify mirror)
			)
		)
		(duplicate_pad_numbers_are_jumpers no)
		(fp_rect
			(start -0.3048 0.9906)
			(end 0.3048 -0.1016)
			(stroke
				(width 0)
				(type default)
			)
			(fill no)
			(layer "B.CrtYd")
		)
		(fp_line
			(start -0.3048 -0.1016)
			(end 0.3048 -0.1016)
			(stroke
				(width 0.1)
				(type default)
			)
			(layer "B.Fab")
		)
		(fp_line
			(start -0.3048 0.9906)
			(end -0.3048 -0.1016)
			(stroke
				(width 0.1)
				(type default)
			)
			(layer "B.Fab")
		)
		(fp_line
			(start 0.3048 -0.1016)
			(end 0.3048 0.9906)
			(stroke
				(width 0.1)
				(type default)
			)
			(layer "B.Fab")
		)
		(fp_line
			(start 0.3048 0.9906)
			(end -0.3048 0.9906)
			(stroke
				(width 0.1)
				(type default)
			)
			(layer "B.Fab")
		)
		(pad "1" smd rect
			(at 0 0 180)
			(size 0.508 0.508)
			(layers "B.Cu" "B.Mask" "B.Paste")
			(net "P3V3_STBY")
		)
		(pad "2" smd rect
			(at 0 0.889 180)
			(size 0.508 0.508)
			(layers "B.Cu" "B.Mask" "B.Paste")
			(net "GND")
		)
		(zone
			(layer "B.Cu")
			(hatch none 0.5)
			(connect_pads
				(clearance 0)
			)
			(min_thickness 0.25)
			(keepout
				(tracks allowed)
				(vias not_allowed)
				(pads allowed)
				(copperpour not_allowed)
				(footprints allowed)
			)
			(placement
				(enabled no)
				(sheetname "")
			)
			(fill
				(thermal_gap 0.5)
				(thermal_bridge_width 0.5)
				(island_removal_mode 0)
			)
			(polygon
				(pts
					(xy -4.62026 -119.97436) (xy -4.11226 -119.97436) (xy -4.11226 -120.35536) (xy -4.62026 -120.35536)
				)
			)
		)
		(zone
			(layer "B.Cu")
			(hatch none 0.5)
			(connect_pads
				(clearance 0)
			)
			(min_thickness 0.25)
			(keepout
				(tracks not_allowed)
				(vias allowed)
				(pads allowed)
				(copperpour not_allowed)
				(footprints allowed)
			)
			(placement
				(enabled no)
				(sheetname "")
			)
			(fill
				(thermal_gap 0.5)
				(thermal_bridge_width 0.5)
				(island_removal_mode 0)
			)
			(polygon
				(pts
					(xy -4.62026 -119.97436) (xy -4.11226 -119.97436) (xy -4.11226 -120.35536) (xy -4.62026 -120.35536)
				)
			)
		)
	)
	(footprint ""
		(layer "B.Cu")
		(at 17.653 -42.291 -90)
		(property "Reference" "R9R12"
			(at 0 0 90)
			(layer "B.SilkS")
			(hide yes)
			(effects
				(font
					(size 1.27 1.27)
				)
				(justify mirror)
			)
		)
		(property "Value" ""
			(at 0 0 90)
			(layer "B.Fab")
			(effects
				(font
					(size 1.27 1.27)
				)
				(justify mirror)
			)
		)
		(duplicate_pad_numbers_are_jumpers no)
		(fp_poly
			(pts
				(xy 0.2794 -0.1016) (xy -0.2794 -0.1016) (xy -0.2794 0.9906) (xy 0.2794 0.9906)
			)
			(stroke
				(width 0)
				(type default)
			)
			(fill no)
			(layer "B.CrtYd")
		)
		(fp_line
			(start -0.2794 0.9906)
			(end -0.2794 -0.1016)
			(stroke
				(width 0.1)
				(type default)
			)
			(layer "B.Fab")
		)
		(fp_line
			(start 0.2794 0.9906)
			(end -0.2794 0.9906)
			(stroke
				(width 0.1)
				(type default)
			)
			(layer "B.Fab")
		)
		(fp_line
			(start -0.2794 -0.1016)
			(end 0.2794 -0.1016)
			(stroke
				(width 0.1)
				(type default)
			)
			(layer "B.Fab")
		)
		(fp_line
			(start 0.2794 -0.1016)
			(end 0.2794 0.9906)
			(stroke
				(width 0.1)
				(type default)
			)
			(layer "B.Fab")
		)
		(pad "1" smd rect
			(at 0 0 90)
			(size 0.508 0.508)
			(layers "B.Cu" "B.Mask" "B.Paste")
			(net "FAN_TACH2")
		)
		(pad "2" smd rect
			(at 0 0.889 90)
			(size 0.508 0.508)
			(layers "B.Cu" "B.Mask" "B.Paste")
			(net "FAN_TACH2_R")
		)
		(zone
			(layer "B.Cu")
			(hatch none 0.5)
			(connect_pads
				(clearance 0)
			)
			(min_thickness 0.25)
			(keepout
				(tracks not_allowed)
				(vias allowed)
				(pads allowed)
				(copperpour not_allowed)
				(footprints allowed)
			)
			(placement
				(enabled no)
				(sheetname "")
			)
			(fill
				(thermal_gap 0.5)
				(thermal_bridge_width 0.5)
				(island_removal_mode 0)
			)
			(polygon
				(pts
					(xy 17.018 -42.037) (xy 17.018 -42.545) (xy 17.399 -42.545) (xy 17.399 -42.037)
				)
			)
		)
		(zone
			(layer "B.Cu")
			(hatch none 0.5)
			(connect_pads
				(clearance 0)
			)
			(min_thickness 0.25)
			(keepout
				(tracks allowed)
				(vias not_allowed)
				(pads allowed)
				(copperpour not_allowed)
				(footprints allowed)
			)
			(placement
				(enabled no)
				(sheetname "")
			)
			(fill
				(thermal_gap 0.5)
				(thermal_bridge_width 0.5)
				(island_removal_mode 0)
			)
			(polygon
				(pts
					(xy 17.399 -42.037) (xy 17.399 -42.545) (xy 17.018 -42.545) (xy 17.018 -42.037)
				)
			)
		)
	)
)
